(kicad_pcb
	(version 20260206)
	(generator "pcbnew")
	(generator_version "10.0")
	(general
		(thickness 1.6)
		(legacy_teardrops no)
	)
	(paper "A4")
	(title_block
		(title "dpb — 14545-sa.0730WZS0815.brd")
		(comment 1 "Honey Badger (Wiwynn) / footprints 672-678 of 1066")
	)
	(layers
		(0 "F.Cu" signal "TOP")
		(4 "In1.Cu" signal "L2GND")
		(6 "In2.Cu" signal "L3")
		(8 "In3.Cu" signal "L4VCC")
		(10 "In4.Cu" signal "L5VCC")
		(12 "In5.Cu" signal "L6")
		(14 "In6.Cu" signal "L7GND")
		(2 "B.Cu" signal "BOTTOM")
		(9 "F.Adhes" user "F.Adhesive")
		(11 "B.Adhes" user "B.Adhesive")
		(13 "F.Paste" user "Package Geometry/Pastemask Top")
		(15 "B.Paste" user "Package Geometry/Pastemask Bottom")
		(5 "F.SilkS" user "Ref Des/Silkscreen Top")
		(7 "B.SilkS" user "Ref Des/Silkscreen Bottom")
		(1 "F.Mask" user "Board Geometry/Soldermask Top")
		(3 "B.Mask" user "Board Geometry/Soldermask Bottom")
		(17 "Dwgs.User" user "User.Drawings")
		(19 "Cmts.User" user "User.Comments")
		(21 "Eco1.User" user "User.Eco1")
		(23 "Eco2.User" user "User.Eco2")
		(25 "Edge.Cuts" user "Board Geometry/Outline")
		(27 "Margin" user)
		(31 "F.CrtYd" user "Package Geometry/Place Bound Top")
		(29 "B.CrtYd" user "Package Geometry/Place Bound Bottom")
		(35 "F.Fab" user "Ref Des/Assembly Top")
		(33 "B.Fab" user "Ref Des/Assembly Bottom")
	)
	(footprint ""
		(layer "F.Cu")
		(at 230.335582 -246.479568 90)
		(property "Reference" "R130"
			(at 0 0 90)
			(layer "F.SilkS")
			(hide yes)
			(effects
				(font
					(size 1.27 1.27)
				)
			)
		)
		(property "Value" "0R2J-2-GP"
			(at 0.064008 -3.993896 90)
			(unlocked yes)
			(layer "F.Fab")
			(hide yes)
			(effects
				(font
					(size 1.016 1.016)
					(thickness 0.1524)
				)
			)
		)
		(property "Device Type" "R402H16"
			(at 0.064008 -5.517896 90)
			(unlocked yes)
			(layer "F.Fab")
			(hide yes)
			(effects
				(font
					(size 1.016 1.016)
					(thickness 0.1524)
				)
			)
		)
		(duplicate_pad_numbers_are_jumpers no)
		(fp_line
			(start 0.508 -0.9398)
			(end -0.508 -0.9398)
			(stroke
				(width 0.1524)
				(type default)
			)
			(layer "F.SilkS")
		)
		(fp_line
			(start -0.508 -0.9398)
			(end -0.508 0.9398)
			(stroke
				(width 0.1524)
				(type default)
			)
			(layer "F.SilkS")
		)
		(fp_rect
			(start -0.508 0.9398)
			(end 0.508 -0.9398)
			(stroke
				(width 0)
				(type default)
			)
			(fill no)
			(layer "F.CrtYd")
		)
		(fp_rect
			(start -0.508 0.9398)
			(end 0.508 -0.9398)
			(stroke
				(width 0)
				(type default)
			)
			(fill no)
			(layer "F.Fab")
		)
		(pad "1" smd custom
			(at 0 -0.4445 90)
			(size 0.1397 0.1397)
			(layers "F.Cu" "F.Mask" "F.Paste")
			(net "DRV_ACT_NET2")
			(options
				(clearance outline)
				(anchor circle)
			)
			(primitives
				(gr_poly
					(pts
						(arc
							(start -0.1778 -0.2794)
							(mid -0.249642 -0.249642)
							(end -0.2794 -0.1778)
						)
						(arc
							(start -0.2794 0.1778)
							(mid -0.249642 0.249642)
							(end -0.1778 0.2794)
						)
						(arc
							(start 0.1778 0.2794)
							(mid 0.249642 0.249642)
							(end 0.2794 0.1778)
						)
						(arc
							(start 0.2794 -0.1778)
							(mid 0.249642 -0.249642)
							(end 0.1778 -0.2794)
						)
					)
					(width 0)
					(fill yes)
				)
			)
		)
		(pad "2" smd custom
			(at 0 0.4445 90)
			(size 0.1397 0.1397)
			(layers "F.Cu" "F.Mask" "F.Paste")
			(net "DRIVE_ACT_2")
			(options
				(clearance outline)
				(anchor circle)
			)
			(primitives
				(gr_poly
					(pts
						(arc
							(start -0.1778 -0.2794)
							(mid -0.249642 -0.249642)
							(end -0.2794 -0.1778)
						)
						(arc
							(start -0.2794 0.1778)
							(mid -0.249642 0.249642)
							(end -0.1778 0.2794)
						)
						(arc
							(start 0.1778 0.2794)
							(mid 0.249642 0.249642)
							(end 0.2794 0.1778)
						)
						(arc
							(start 0.2794 -0.1778)
							(mid 0.249642 -0.249642)
							(end 0.1778 -0.2794)
						)
					)
					(width 0)
					(fill yes)
				)
			)
		)
	)
	(footprint ""
		(layer "F.Cu")
		(at 81.152746 -193.8147)
		(property "Reference" "Q18"
			(at 0 0 0)
			(layer "F.SilkS")
			(hide yes)
			(effects
				(font
					(size 1.27 1.27)
				)
			)
		)
		(property "Value" "2N7002DW-7F-GP"
			(at -2.3622 -8.2042 0)
			(unlocked yes)
			(layer "F.Fab")
			(hide yes)
			(effects
				(font
					(size 1.016 1.016)
					(thickness 0.1524)
				)
			)
		)
		(property "Device Type" "SOT-363H44"
			(at -2.3622 -10.1092 0)
			(unlocked yes)
			(layer "F.Fab")
			(hide yes)
			(effects
				(font
					(size 1.016 1.016)
					(thickness 0.1524)
				)
			)
		)
		(duplicate_pad_numbers_are_jumpers no)
		(fp_line
			(start -1.4478 -1.7018)
			(end -1.4478 1.7018)
			(stroke
				(width 0.1524)
				(type default)
			)
			(layer "F.SilkS")
		)
		(fp_line
			(start -1.4478 1.7018)
			(end 1.4478 1.7018)
			(stroke
				(width 0.1524)
				(type default)
			)
			(layer "F.SilkS")
		)
		(fp_line
			(start -1.27 1.524)
			(end -1.27 0.6604)
			(stroke
				(width 0.4826)
				(type default)
			)
			(layer "F.SilkS")
		)
		(fp_line
			(start 1.4478 -1.7018)
			(end -1.4478 -1.7018)
			(stroke
				(width 0.1524)
				(type default)
			)
			(layer "F.SilkS")
		)
		(fp_line
			(start 1.4478 1.7018)
			(end 1.4478 -1.7018)
			(stroke
				(width 0.1524)
				(type default)
			)
			(layer "F.SilkS")
		)
		(fp_poly
			(pts
				(xy -1.524 -1.778) (xy 1.524 -1.778) (xy 1.524 1.778) (xy -1.524 1.778)
			)
			(stroke
				(width 0)
				(type default)
			)
			(fill no)
			(layer "F.CrtYd")
		)
		(fp_poly
			(pts
				(xy -1.524 -1.778) (xy 1.524 -1.778) (xy 1.524 1.778) (xy -1.524 1.778)
			)
			(stroke
				(width 0)
				(type default)
			)
			(fill no)
			(layer "F.Fab")
		)
		(pad "1" smd rect
			(at -0.65024 0.9398)
			(size 0.4064 1.016)
			(layers "F.Cu" "F.Mask" "F.Paste")
			(net "GND")
		)
		(pad "2" smd rect
			(at 0 0.9398)
			(size 0.4064 1.016)
			(layers "F.Cu" "F.Mask" "F.Paste")
			(net "SW_PWR_R_HDD8")
		)
		(pad "3" smd rect
			(at 0.65024 0.9398)
			(size 0.4064 1.016)
			(layers "F.Cu" "F.Mask" "F.Paste")
			(net "SW_HDD8_P")
		)
		(pad "4" smd rect
			(at 0.65024 -0.9398)
			(size 0.4064 1.016)
			(layers "F.Cu" "F.Mask" "F.Paste")
			(net "GND")
		)
		(pad "5" smd rect
			(at 0 -0.9398)
			(size 0.4064 1.016)
			(layers "F.Cu" "F.Mask" "F.Paste")
			(net "SW_HDD8_G")
		)
		(pad "6" smd rect
			(at -0.65024 -0.9398)
			(size 0.4064 1.016)
			(layers "F.Cu" "F.Mask" "F.Paste")
			(net "SW_HDD8_R")
		)
	)
	(footprint ""
		(layer "F.Cu")
		(at 215.645746 -286.9057 -90)
		(property "Reference" "R138"
			(at 0 0 270)
			(layer "F.SilkS")
			(hide yes)
			(effects
				(font
					(size 1.27 1.27)
				)
			)
		)
		(property "Value" "2R2010J-1-GP"
			(at 0.254 -8.0772 270)
			(unlocked yes)
			(layer "F.Fab")
			(hide yes)
			(effects
				(font
					(size 1.016 1.016)
					(thickness 0.1524)
				)
			)
		)
		(property "Device Type" "R2010H28"
			(at 0.254 -9.6774 270)
			(unlocked yes)
			(layer "F.Fab")
			(hide yes)
			(effects
				(font
					(size 1.016 1.016)
					(thickness 0.1524)
				)
			)
		)
		(duplicate_pad_numbers_are_jumpers no)
		(fp_line
			(start -1.651 3.302)
			(end 1.651 3.302)
			(stroke
				(width 0.1524)
				(type default)
			)
			(layer "F.SilkS")
		)
		(fp_line
			(start 1.651 3.302)
			(end 1.651 -3.302)
			(stroke
				(width 0.1524)
				(type default)
			)
			(layer "F.SilkS")
		)
		(fp_line
			(start -1.651 -3.302)
			(end -1.651 3.302)
			(stroke
				(width 0.1524)
				(type default)
			)
			(layer "F.SilkS")
		)
		(fp_line
			(start 1.651 -3.302)
			(end -1.651 -3.302)
			(stroke
				(width 0.1524)
				(type default)
			)
			(layer "F.SilkS")
		)
		(fp_rect
			(start -1.7272 -3.3782)
			(end 1.7272 3.3782)
			(stroke
				(width 0)
				(type default)
			)
			(fill no)
			(layer "F.CrtYd")
		)
		(fp_poly
			(pts
				(xy 1.7272 3.3782) (xy 1.7272 -3.3782) (xy -1.7272 -3.3782) (xy -1.7272 3.3782)
			)
			(stroke
				(width 0)
				(type default)
			)
			(fill no)
			(layer "F.Fab")
		)
		(pad "1" smd rect
			(at 0 -2.3495 270)
			(size 2.794 1.143)
			(layers "F.Cu" "F.Mask" "F.Paste")
			(net "12V_PRE_2")
		)
		(pad "2" smd rect
			(at 0 2.3495 270)
			(size 2.794 1.143)
			(layers "F.Cu" "F.Mask" "F.Paste")
			(net "P12V_HDD2")
		)
	)
	(footprint ""
		(layer "F.Cu")
		(at 190.754 -495.046 180)
		(property "Reference" "R112"
			(at 0 0 180)
			(layer "F.SilkS")
			(hide yes)
			(effects
				(font
					(size 1.27 1.27)
				)
			)
		)
		(property "Value" "0R2J-2-GP"
			(at 0.064008 -3.993896 180)
			(unlocked yes)
			(layer "F.Fab")
			(hide yes)
			(effects
				(font
					(size 1.016 1.016)
					(thickness 0.1524)
				)
			)
		)
		(property "Device Type" "R402H16"
			(at 0.064008 -5.517896 180)
			(unlocked yes)
			(layer "F.Fab")
			(hide yes)
			(effects
				(font
					(size 1.016 1.016)
					(thickness 0.1524)
				)
			)
		)
		(duplicate_pad_numbers_are_jumpers no)
		(fp_line
			(start 0.508 -0.9398)
			(end -0.508 -0.9398)
			(stroke
				(width 0.1524)
				(type default)
			)
			(layer "F.SilkS")
		)
		(fp_line
			(start -0.508 -0.9398)
			(end -0.508 0.9398)
			(stroke
				(width 0.1524)
				(type default)
			)
			(layer "F.SilkS")
		)
		(fp_rect
			(start -0.508 0.9398)
			(end 0.508 -0.9398)
			(stroke
				(width 0)
				(type default)
			)
			(fill no)
			(layer "F.CrtYd")
		)
		(fp_rect
			(start -0.508 0.9398)
			(end 0.508 -0.9398)
			(stroke
				(width 0)
				(type default)
			)
			(fill no)
			(layer "F.Fab")
		)
		(pad "1" smd custom
			(at 0 -0.4445 180)
			(size 0.1397 0.1397)
			(layers "F.Cu" "F.Mask" "F.Paste")
			(net "SW_PWR_HDD0")
			(options
				(clearance outline)
				(anchor circle)
			)
			(primitives
				(gr_poly
					(pts
						(arc
							(start -0.1778 -0.2794)
							(mid -0.249642 -0.249642)
							(end -0.2794 -0.1778)
						)
						(arc
							(start -0.2794 0.1778)
							(mid -0.249642 0.249642)
							(end -0.1778 0.2794)
						)
						(arc
							(start 0.1778 0.2794)
							(mid 0.249642 0.249642)
							(end 0.2794 0.1778)
						)
						(arc
							(start 0.2794 -0.1778)
							(mid 0.249642 -0.249642)
							(end 0.1778 -0.2794)
						)
					)
					(width 0)
					(fill yes)
				)
			)
		)
		(pad "2" smd custom
			(at 0 0.4445 180)
			(size 0.1397 0.1397)
			(layers "F.Cu" "F.Mask" "F.Paste")
			(net "SW_PWR_R_HDD0")
			(options
				(clearance outline)
				(anchor circle)
			)
			(primitives
				(gr_poly
					(pts
						(arc
							(start -0.1778 -0.2794)
							(mid -0.249642 -0.249642)
							(end -0.2794 -0.1778)
						)
						(arc
							(start -0.2794 0.1778)
							(mid -0.249642 0.249642)
							(end -0.1778 0.2794)
						)
						(arc
							(start 0.1778 0.2794)
							(mid 0.249642 0.249642)
							(end 0.2794 0.1778)
						)
						(arc
							(start 0.2794 -0.1778)
							(mid 0.249642 -0.249642)
							(end 0.1778 -0.2794)
						)
					)
					(width 0)
					(fill yes)
				)
			)
		)
	)
	(footprint ""
		(layer "F.Cu")
		(at 5.969 -29.083 -90)
		(property "Reference" "C132"
			(at 0 0 270)
			(layer "F.SilkS")
			(hide yes)
			(effects
				(font
					(size 1.27 1.27)
				)
			)
		)
		(property "Value" "SC1U25V3KX-1-GP"
			(at 0 -2.8194 270)
			(unlocked yes)
			(layer "F.Fab")
			(hide yes)
			(effects
				(font
					(size 1.016 1.016)
					(thickness 0.1524)
				)
			)
		)
		(property "Device Type" "C603H36"
			(at 0 -4.3434 270)
			(unlocked yes)
			(layer "F.Fab")
			(hide yes)
			(effects
				(font
					(size 1.016 1.016)
					(thickness 0.1524)
				)
			)
		)
		(duplicate_pad_numbers_are_jumpers no)
		(fp_line
			(start 0.508 0)
			(end -0.508 0)
			(stroke
				(width 0.2032)
				(type default)
			)
			(layer "F.SilkS")
		)
		(fp_rect
			(start -0.5842 1.3335)
			(end 0.5842 -1.3335)
			(stroke
				(width 0)
				(type default)
			)
			(fill no)
			(layer "F.CrtYd")
		)
		(fp_rect
			(start -0.5842 1.3335)
			(end 0.5842 -1.3335)
			(stroke
				(width 0)
				(type default)
			)
			(fill no)
			(layer "F.Fab")
		)
		(pad "1" smd custom
			(at 0 -0.762 270)
			(size 0.2159 0.2159)
			(layers "F.Cu" "F.Mask" "F.Paste")
			(net "P12V")
			(options
				(clearance outline)
				(anchor circle)
			)
			(primitives
				(gr_poly
					(pts
						(arc
							(start -0.3302 -0.4318)
							(mid -0.402042 -0.402042)
							(end -0.4318 -0.3302)
						)
						(arc
							(start -0.4318 0.3302)
							(mid -0.402042 0.402042)
							(end -0.3302 0.4318)
						)
						(arc
							(start 0.3302 0.4318)
							(mid 0.402042 0.402042)
							(end 0.4318 0.3302)
						)
						(arc
							(start 0.4318 -0.3302)
							(mid 0.402042 -0.402042)
							(end 0.3302 -0.4318)
						)
					)
					(width 0)
					(fill yes)
				)
			)
		)
		(pad "2" smd custom
			(at 0 0.762 270)
			(size 0.2159 0.2159)
			(layers "F.Cu" "F.Mask" "F.Paste")
			(net "GND")
			(options
				(clearance outline)
				(anchor circle)
			)
			(primitives
				(gr_poly
					(pts
						(arc
							(start -0.3302 -0.4318)
							(mid -0.402042 -0.402042)
							(end -0.4318 -0.3302)
						)
						(arc
							(start -0.4318 0.3302)
							(mid -0.402042 0.402042)
							(end -0.3302 0.4318)
						)
						(arc
							(start 0.3302 0.4318)
							(mid 0.402042 0.402042)
							(end 0.4318 0.3302)
						)
						(arc
							(start 0.4318 -0.3302)
							(mid 0.402042 -0.402042)
							(end 0.3302 -0.4318)
						)
					)
					(width 0)
					(fill yes)
				)
			)
		)
	)
	(footprint ""
		(layer "F.Cu")
		(at 62.563756 -492.661702)
		(property "Reference" "C191"
			(at 0 0 0)
			(layer "F.SilkS")
			(hide yes)
			(effects
				(font
					(size 1.27 1.27)
				)
			)
		)
		(property "Value" "SC10U25V6KX-1GP"
			(at -0.0762 -5.1308 0)
			(unlocked yes)
			(layer "F.Fab")
			(hide yes)
			(effects
				(font
					(size 1.016 1.016)
					(thickness 0.1524)
				)
			)
		)
		(property "Device Type" "C1206H71"
			(at -0.127 -6.6548 0)
			(unlocked yes)
			(layer "F.Fab")
			(hide yes)
			(effects
				(font
					(size 1.016 1.016)
					(thickness 0.1524)
				)
			)
		)
		(duplicate_pad_numbers_are_jumpers no)
		(fp_line
			(start -1.016 -2.2352)
			(end 1.016 -2.2352)
			(stroke
				(width 0.1524)
				(type default)
			)
			(layer "F.SilkS")
		)
		(fp_line
			(start -1.016 -0.8382)
			(end -1.016 -2.2352)
			(stroke
				(width 0.1524)
				(type default)
			)
			(layer "F.SilkS")
		)
		(fp_line
			(start -1.016 2.2352)
			(end -1.016 0.8382)
			(stroke
				(width 0.1524)
				(type default)
			)
			(layer "F.SilkS")
		)
		(fp_line
			(start 1.016 -2.2352)
			(end 1.016 -0.8382)
			(stroke
				(width 0.1524)
				(type default)
			)
			(layer "F.SilkS")
		)
		(fp_line
			(start 1.016 0.8382)
			(end 1.016 2.2352)
			(stroke
				(width 0.1524)
				(type default)
			)
			(layer "F.SilkS")
		)
		(fp_line
			(start 1.016 2.2352)
			(end -1.016 2.2352)
			(stroke
				(width 0.1524)
				(type default)
			)
			(layer "F.SilkS")
		)
		(fp_rect
			(start -1.0922 2.3114)
			(end 1.0922 -2.3114)
			(stroke
				(width 0)
				(type default)
			)
			(fill no)
			(layer "F.CrtYd")
		)
		(fp_poly
			(pts
				(xy 1.0922 -2.3114) (xy 1.0922 2.3114) (xy -1.0922 2.3114) (xy -1.0922 -2.3114)
			)
			(stroke
				(width 0)
				(type default)
			)
			(fill no)
			(layer "F.Fab")
		)
		(pad "1" smd rect
			(at 0 -1.397)
			(size 1.651 1.27)
			(layers "F.Cu" "F.Mask" "F.Paste")
			(net "P12V_HDD5")
		)
		(pad "2" smd rect
			(at 0 1.397)
			(size 1.651 1.27)
			(layers "F.Cu" "F.Mask" "F.Paste")
			(net "GND")
		)
	)
	(footprint ""
		(layer "F.Cu")
		(at 193.802 -293.878 180)
		(property "Reference" "R565"
			(at 0 0 180)
			(layer "F.SilkS")
			(hide yes)
			(effects
				(font
					(size 1.27 1.27)
				)
			)
		)
		(property "Value" "300KR2F-GP"
			(at 0.064008 -3.993896 180)
			(unlocked yes)
			(layer "F.Fab")
			(hide yes)
			(effects
				(font
					(size 1.016 1.016)
					(thickness 0.1524)
				)
			)
		)
		(property "Device Type" "R402H16"
			(at 0.064008 -5.517896 180)
			(unlocked yes)
			(layer "F.Fab")
			(hide yes)
			(effects
				(font
					(size 1.016 1.016)
					(thickness 0.1524)
				)
			)
		)
		(duplicate_pad_numbers_are_jumpers no)
		(fp_line
			(start 0.508 -0.9398)
			(end -0.508 -0.9398)
			(stroke
				(width 0.1524)
				(type default)
			)
			(layer "F.SilkS")
		)
		(fp_line
			(start -0.508 -0.9398)
			(end -0.508 0.9398)
			(stroke
				(width 0.1524)
				(type default)
			)
			(layer "F.SilkS")
		)
		(fp_rect
			(start -0.508 0.9398)
			(end 0.508 -0.9398)
			(stroke
				(width 0)
				(type default)
			)
			(fill no)
			(layer "F.CrtYd")
		)
		(fp_rect
			(start -0.508 0.9398)
			(end 0.508 -0.9398)
			(stroke
				(width 0)
				(type default)
			)
			(fill no)
			(layer "F.Fab")
		)
		(pad "1" smd custom
			(at 0 -0.4445 180)
			(size 0.1397 0.1397)
			(layers "F.Cu" "F.Mask" "F.Paste")
			(net "SW_HDD2_N")
			(options
				(clearance outline)
				(anchor circle)
			)
			(primitives
				(gr_poly
					(pts
						(arc
							(start -0.1778 -0.2794)
							(mid -0.249642 -0.249642)
							(end -0.2794 -0.1778)
						)
						(arc
							(start -0.2794 0.1778)
							(mid -0.249642 0.249642)
							(end -0.1778 0.2794)
						)
						(arc
							(start 0.1778 0.2794)
							(mid 0.249642 0.249642)
							(end 0.2794 0.1778)
						)
						(arc
							(start 0.2794 -0.1778)
							(mid 0.249642 -0.249642)
							(end 0.1778 -0.2794)
						)
					)
					(width 0)
					(fill yes)
				)
			)
		)
		(pad "2" smd custom
			(at 0 0.4445 180)
			(size 0.1397 0.1397)
			(layers "F.Cu" "F.Mask" "F.Paste")
			(net "P12V")
			(options
				(clearance outline)
				(anchor circle)
			)
			(primitives
				(gr_poly
					(pts
						(arc
							(start -0.1778 -0.2794)
							(mid -0.249642 -0.249642)
							(end -0.2794 -0.1778)
						)
						(arc
							(start -0.2794 0.1778)
							(mid -0.249642 0.249642)
							(end -0.1778 0.2794)
						)
						(arc
							(start 0.1778 0.2794)
							(mid 0.249642 0.249642)
							(end 0.2794 0.1778)
						)
						(arc
							(start 0.2794 -0.1778)
							(mid 0.249642 -0.249642)
							(end 0.1778 -0.2794)
						)
					)
					(width 0)
					(fill yes)
				)
			)
		)
	)
)
